(kicad_pcb
	(version 20260206)
	(generator "pcbnew")
	(generator_version "10.0")
	(general
		(thickness 1.6)
		(legacy_teardrops no)
	)
	(paper "A4")
	(title_block
		(title "panther-plus-userver — 13130-1b_20150205.brd")
		(comment 1 "Honey Badger (Wiwynn) / footprint 624 of 1509 (DIMM4), pads 65-71 of 210")
	)
	(layers
		(0 "F.Cu" signal "TOP")
		(4 "In1.Cu" signal "L2")
		(6 "In2.Cu" signal "L3")
		(8 "In3.Cu" signal "L4")
		(10 "In4.Cu" signal "L5")
		(12 "In5.Cu" signal "L6")
		(14 "In6.Cu" signal "L7")
		(16 "In7.Cu" signal "L8")
		(18 "In8.Cu" signal "L9")
		(20 "In9.Cu" signal "L10")
		(22 "In10.Cu" signal "L11")
		(2 "B.Cu" signal "BOTTOM")
		(9 "F.Adhes" user "F.Adhesive")
		(11 "B.Adhes" user "B.Adhesive")
		(13 "F.Paste" user "Package Geometry/Pastemask Top")
		(15 "B.Paste" user "Package Geometry/Pastemask Bottom")
		(5 "F.SilkS" user "Ref Des/Silkscreen Top")
		(7 "B.SilkS" user "Ref Des/Silkscreen Bottom")
		(1 "F.Mask" user "Board Geometry/Soldermask Top")
		(3 "B.Mask" user "Board Geometry/Soldermask Bottom")
		(17 "Dwgs.User" user "User.Drawings")
		(19 "Cmts.User" user "User.Comments")
		(21 "Eco1.User" user "User.Eco1")
		(23 "Eco2.User" user "User.Eco2")
		(25 "Edge.Cuts" user "Board Geometry/Outline")
		(27 "Margin" user)
		(31 "F.CrtYd" user "Package Geometry/Place Bound Top")
		(29 "B.CrtYd" user "Package Geometry/Place Bound Bottom")
		(35 "F.Fab" user "Ref Des/Assembly Top")
		(33 "B.Fab" user "Ref Des/Assembly Bottom")
	)
	(footprint ""
		(layer "F.Cu")
		(at 159.999934 -5.790692)
		(property "Reference" "DIMM4"
			(at 0 0 0)
			(layer "F.SilkS")
			(hide yes)
			(effects
				(font
					(size 1.27 1.27)
				)
			)
		)
		(property "Value" "DDR3-204P-174-COLAY-1-GP"
			(at -40.682164 -17.468088 0)
			(unlocked yes)
			(layer "F.Fab")
			(hide yes)
			(effects
				(font
					(size 1.016 1.016)
					(thickness 0.1524)
				)
			)
		)
		(property "Device Type" "AS0A626-H8SN-7H-COLAY-1"
			(at -40.682164 -18.992088 0)
			(unlocked yes)
			(layer "F.Fab")
			(hide yes)
			(effects
				(font
					(size 1.016 1.016)
					(thickness 0.1524)
				)
			)
		)
		(duplicate_pad_numbers_are_jumpers no)
		(pad "63" smd custom
			(at -13.050012 4.106672)
			(size 0.1143 0.1143)
			(layers "F.Cu" "F.Mask" "F.Paste")
			(net "M_B_DQ30")
			(options
				(clearance outline)
				(anchor circle)
			)
			(primitives
				(gr_poly
					(pts
						(xy 0 0.9017) (xy -0.03175 0.89916) (xy -0.0635 0.889) (xy -0.09144 0.87376) (xy -0.11684 0.85344)
						(xy -0.13716 0.82804) (xy -0.1524 0.8001) (xy -0.16256 0.76835) (xy -0.1651 0.7366) (xy -0.1651 0.11938)
						(xy -0.17272 0.11176) (xy -0.19812 0.0762) (xy -0.2032 0.06604) (xy -0.20701 0.05715) (xy -0.21209 0.04699)
						(xy -0.2159 0.03683) (xy -0.21844 0.02667) (xy -0.22225 0.01524) (xy -0.22352 0.00508) (xy -0.22606 -0.00508)
						(xy -0.22733 -0.01651) (xy -0.22733 -0.02667) (xy -0.2286 -0.0381) (xy -0.22733 -0.04953) (xy -0.22733 -0.05969)
						(xy -0.22606 -0.07112) (xy -0.22352 -0.08128) (xy -0.22225 -0.09144) (xy -0.21844 -0.10287) (xy -0.2159 -0.11303)
						(xy -0.21209 -0.12319) (xy -0.20701 -0.13335) (xy -0.2032 -0.14224) (xy -0.19812 -0.1524) (xy -0.17272 -0.18796)
						(xy -0.1651 -0.19558) (xy -0.1651 -0.7366) (xy -0.16256 -0.76835) (xy -0.1524 -0.8001) (xy -0.13716 -0.82804)
						(xy -0.11684 -0.85344) (xy -0.09144 -0.87376) (xy -0.0635 -0.889) (xy -0.03175 -0.89916) (xy 0 -0.9017)
						(xy 0.03175 -0.89916) (xy 0.0635 -0.889) (xy 0.09144 -0.87376) (xy 0.11684 -0.85344) (xy 0.13716 -0.82804)
						(xy 0.1524 -0.8001) (xy 0.16256 -0.76835) (xy 0.1651 -0.7366) (xy 0.1651 -0.19685) (xy 0.17272 -0.18923)
						(xy 0.17907 -0.18034) (xy 0.18669 -0.17145) (xy 0.19177 -0.16256) (xy 0.19812 -0.15367) (xy 0.20828 -0.13335)
						(xy 0.21971 -0.10287) (xy 0.22225 -0.09271) (xy 0.22479 -0.08128) (xy 0.22606 -0.07112) (xy 0.2286 -0.05969)
						(xy 0.2286 -0.01651) (xy 0.22606 -0.00508) (xy 0.22479 0.00508) (xy 0.22225 0.01651) (xy 0.21971 0.02667)
						(xy 0.20828 0.05715) (xy 0.19812 0.07747) (xy 0.19177 0.08636) (xy 0.18669 0.09525) (xy 0.17907 0.10414)
						(xy 0.17272 0.11303) (xy 0.1651 0.12065) (xy 0.1651 0.7366) (xy 0.16256 0.76835) (xy 0.1524 0.8001)
						(xy 0.13716 0.82804) (xy 0.11684 0.85344) (xy 0.09144 0.87376) (xy 0.0635 0.889) (xy 0.03175 0.89916)
					)
					(width 0)
					(fill yes)
				)
			)
		)
		(pad "64" smd custom
			(at -12.750038 -4.106672)
			(size 0.1143 0.1143)
			(layers "F.Cu" "F.Mask" "F.Paste")
			(net "GND")
			(options
				(clearance outline)
				(anchor circle)
			)
			(primitives
				(gr_poly
					(pts
						(xy 0 0.9017) (xy -0.03175 0.89916) (xy -0.0635 0.889) (xy -0.09144 0.87376) (xy -0.11684 0.85344)
						(xy -0.13716 0.82804) (xy -0.1524 0.8001) (xy -0.16256 0.76835) (xy -0.1651 0.7366) (xy -0.1651 0.19685)
						(xy -0.17272 0.18923) (xy -0.17907 0.18034) (xy -0.18669 0.17145) (xy -0.19177 0.16256) (xy -0.19812 0.15367)
						(xy -0.20828 0.13335) (xy -0.21971 0.10287) (xy -0.22225 0.09271) (xy -0.22479 0.08128) (xy -0.22606 0.07112)
						(xy -0.2286 0.05969) (xy -0.2286 0.01651) (xy -0.22606 0.00508) (xy -0.22479 -0.00508) (xy -0.22225 -0.01651)
						(xy -0.21971 -0.02667) (xy -0.20828 -0.05715) (xy -0.19812 -0.07747) (xy -0.19177 -0.08636) (xy -0.18669 -0.09525)
						(xy -0.17907 -0.10414) (xy -0.17272 -0.11303) (xy -0.1651 -0.12065) (xy -0.1651 -0.7366) (xy -0.16256 -0.76835)
						(xy -0.1524 -0.8001) (xy -0.13716 -0.82804) (xy -0.11684 -0.85344) (xy -0.09144 -0.87376) (xy -0.0635 -0.889)
						(xy -0.03175 -0.89916) (xy 0 -0.9017) (xy 0.03175 -0.89916) (xy 0.0635 -0.889) (xy 0.09144 -0.87376)
						(xy 0.11684 -0.85344) (xy 0.13716 -0.82804) (xy 0.1524 -0.8001) (xy 0.16256 -0.76835) (xy 0.1651 -0.7366)
						(xy 0.1651 -0.11938) (xy 0.17272 -0.11176) (xy 0.19812 -0.0762) (xy 0.2032 -0.06604) (xy 0.20701 -0.05715)
						(xy 0.21209 -0.04699) (xy 0.2159 -0.03683) (xy 0.21844 -0.02667) (xy 0.22225 -0.01524) (xy 0.22352 -0.00508)
						(xy 0.22606 0.00508) (xy 0.22733 0.01651) (xy 0.22733 0.02667) (xy 0.2286 0.0381) (xy 0.22733 0.04953)
						(xy 0.22733 0.05969) (xy 0.22606 0.07112) (xy 0.22352 0.08128) (xy 0.22225 0.09144) (xy 0.21844 0.10287)
						(xy 0.2159 0.11303) (xy 0.21209 0.12319) (xy 0.20701 0.13335) (xy 0.2032 0.14224) (xy 0.19812 0.1524)
						(xy 0.17272 0.18796) (xy 0.1651 0.19558) (xy 0.1651 0.7366) (xy 0.16256 0.76835) (xy 0.1524 0.8001)
						(xy 0.13716 0.82804) (xy 0.11684 0.85344) (xy 0.09144 0.87376) (xy 0.0635 0.889) (xy 0.03175 0.89916)
					)
					(width 0)
					(fill yes)
				)
			)
		)
		(pad "65" smd custom
			(at -12.450064 4.106672)
			(size 0.1143 0.1143)
			(layers "F.Cu" "F.Mask" "F.Paste")
			(net "M_B_DQ31")
			(options
				(clearance outline)
				(anchor circle)
			)
			(primitives
				(gr_poly
					(pts
						(xy 0 0.9017) (xy -0.03175 0.89916) (xy -0.0635 0.889) (xy -0.09144 0.87376) (xy -0.11684 0.85344)
						(xy -0.13716 0.82804) (xy -0.1524 0.8001) (xy -0.16256 0.76835) (xy -0.1651 0.7366) (xy -0.1651 -0.13462)
						(xy -0.17272 -0.14224) (xy -0.19812 -0.1778) (xy -0.2032 -0.18796) (xy -0.20701 -0.19685) (xy -0.21209 -0.20701)
						(xy -0.2159 -0.21717) (xy -0.21844 -0.22733) (xy -0.22225 -0.23876) (xy -0.22352 -0.24892) (xy -0.22606 -0.25908)
						(xy -0.22733 -0.27051) (xy -0.22733 -0.28067) (xy -0.2286 -0.2921) (xy -0.22733 -0.30353) (xy -0.22733 -0.31369)
						(xy -0.22606 -0.32512) (xy -0.22352 -0.33528) (xy -0.22225 -0.34544) (xy -0.21844 -0.35687) (xy -0.2159 -0.36703)
						(xy -0.21209 -0.37719) (xy -0.20701 -0.38735) (xy -0.2032 -0.39624) (xy -0.19812 -0.4064) (xy -0.17272 -0.44196)
						(xy -0.1651 -0.44958) (xy -0.1651 -0.7366) (xy -0.16256 -0.76835) (xy -0.1524 -0.8001) (xy -0.13716 -0.82804)
						(xy -0.11684 -0.85344) (xy -0.09144 -0.87376) (xy -0.0635 -0.889) (xy -0.03175 -0.89916) (xy 0 -0.9017)
						(xy 0.03175 -0.89916) (xy 0.0635 -0.889) (xy 0.09144 -0.87376) (xy 0.11684 -0.85344) (xy 0.13716 -0.82804)
						(xy 0.1524 -0.8001) (xy 0.16256 -0.76835) (xy 0.1651 -0.7366) (xy 0.1651 -0.44958) (xy 0.17272 -0.44196)
						(xy 0.19812 -0.4064) (xy 0.2032 -0.39624) (xy 0.20701 -0.38735) (xy 0.21209 -0.37719) (xy 0.2159 -0.36703)
						(xy 0.21844 -0.35687) (xy 0.22225 -0.34544) (xy 0.22352 -0.33528) (xy 0.22606 -0.32512) (xy 0.22733 -0.31369)
						(xy 0.22733 -0.30353) (xy 0.2286 -0.2921) (xy 0.22733 -0.28067) (xy 0.22733 -0.27051) (xy 0.22606 -0.25908)
						(xy 0.22352 -0.24892) (xy 0.22225 -0.23876) (xy 0.21844 -0.22733) (xy 0.2159 -0.21717) (xy 0.21209 -0.20701)
						(xy 0.20701 -0.19685) (xy 0.2032 -0.18796) (xy 0.19812 -0.1778) (xy 0.17272 -0.14224) (xy 0.1651 -0.13462)
						(xy 0.1651 0.7366) (xy 0.16256 0.76835) (xy 0.1524 0.8001) (xy 0.13716 0.82804) (xy 0.11684 0.85344)
						(xy 0.09144 0.87376) (xy 0.0635 0.889) (xy 0.03175 0.89916)
					)
					(width 0)
					(fill yes)
				)
			)
		)
		(pad "66" smd custom
			(at -12.15009 -4.106672)
			(size 0.1143 0.1143)
			(layers "F.Cu" "F.Mask" "F.Paste")
			(net "M_B_DQ26")
			(options
				(clearance outline)
				(anchor circle)
			)
			(primitives
				(gr_poly
					(pts
						(xy 0 0.9017) (xy -0.03175 0.89916) (xy -0.0635 0.889) (xy -0.09144 0.87376) (xy -0.11684 0.85344)
						(xy -0.13716 0.82804) (xy -0.1524 0.8001) (xy -0.16256 0.76835) (xy -0.1651 0.7366) (xy -0.1651 0.44958)
						(xy -0.17272 0.44196) (xy -0.19812 0.4064) (xy -0.2032 0.39624) (xy -0.20701 0.38735) (xy -0.21209 0.37719)
						(xy -0.2159 0.36703) (xy -0.21844 0.35687) (xy -0.22225 0.34544) (xy -0.22352 0.33528) (xy -0.22606 0.32512)
						(xy -0.22733 0.31369) (xy -0.22733 0.30353) (xy -0.2286 0.2921) (xy -0.22733 0.28067) (xy -0.22733 0.27051)
						(xy -0.22606 0.25908) (xy -0.22352 0.24892) (xy -0.22225 0.23876) (xy -0.21844 0.22733) (xy -0.2159 0.21717)
						(xy -0.21209 0.20701) (xy -0.20701 0.19685) (xy -0.2032 0.18796) (xy -0.19812 0.1778) (xy -0.17272 0.14224)
						(xy -0.1651 0.13462) (xy -0.1651 -0.7366) (xy -0.16256 -0.76835) (xy -0.1524 -0.8001) (xy -0.13716 -0.82804)
						(xy -0.11684 -0.85344) (xy -0.09144 -0.87376) (xy -0.0635 -0.889) (xy -0.03175 -0.89916) (xy 0 -0.9017)
						(xy 0.03175 -0.89916) (xy 0.0635 -0.889) (xy 0.09144 -0.87376) (xy 0.11684 -0.85344) (xy 0.13716 -0.82804)
						(xy 0.1524 -0.8001) (xy 0.16256 -0.76835) (xy 0.1651 -0.7366) (xy 0.1651 0.13462) (xy 0.17272 0.14224)
						(xy 0.19812 0.1778) (xy 0.2032 0.18796) (xy 0.20701 0.19685) (xy 0.21209 0.20701) (xy 0.2159 0.21717)
						(xy 0.21844 0.22733) (xy 0.22225 0.23876) (xy 0.22352 0.24892) (xy 0.22606 0.25908) (xy 0.22733 0.27051)
						(xy 0.22733 0.28067) (xy 0.2286 0.2921) (xy 0.22733 0.30353) (xy 0.22733 0.31369) (xy 0.22606 0.32512)
						(xy 0.22352 0.33528) (xy 0.22225 0.34544) (xy 0.21844 0.35687) (xy 0.2159 0.36703) (xy 0.21209 0.37719)
						(xy 0.20701 0.38735) (xy 0.2032 0.39624) (xy 0.19812 0.4064) (xy 0.17272 0.44196) (xy 0.1651 0.44958)
						(xy 0.1651 0.7366) (xy 0.16256 0.76835) (xy 0.1524 0.8001) (xy 0.13716 0.82804) (xy 0.11684 0.85344)
						(xy 0.09144 0.87376) (xy 0.0635 0.889) (xy 0.03175 0.89916)
					)
					(width 0)
					(fill yes)
				)
			)
		)
		(pad "67" smd custom
			(at -11.850116 4.106672)
			(size 0.1143 0.1143)
			(layers "F.Cu" "F.Mask" "F.Paste")
			(net "GND")
			(options
				(clearance outline)
				(anchor circle)
			)
			(primitives
				(gr_poly
					(pts
						(xy 0 0.9017) (xy -0.03175 0.89916) (xy -0.0635 0.889) (xy -0.09144 0.87376) (xy -0.11684 0.85344)
						(xy -0.13716 0.82804) (xy -0.1524 0.8001) (xy -0.16256 0.76835) (xy -0.1651 0.7366) (xy -0.1651 0.11938)
						(xy -0.17272 0.11176) (xy -0.19812 0.0762) (xy -0.2032 0.06604) (xy -0.20701 0.05715) (xy -0.21209 0.04699)
						(xy -0.2159 0.03683) (xy -0.21844 0.02667) (xy -0.22225 0.01524) (xy -0.22352 0.00508) (xy -0.22606 -0.00508)
						(xy -0.22733 -0.01651) (xy -0.22733 -0.02667) (xy -0.2286 -0.0381) (xy -0.22733 -0.04953) (xy -0.22733 -0.05969)
						(xy -0.22606 -0.07112) (xy -0.22352 -0.08128) (xy -0.22225 -0.09144) (xy -0.21844 -0.10287) (xy -0.2159 -0.11303)
						(xy -0.21209 -0.12319) (xy -0.20701 -0.13335) (xy -0.2032 -0.14224) (xy -0.19812 -0.1524) (xy -0.17272 -0.18796)
						(xy -0.1651 -0.19558) (xy -0.1651 -0.7366) (xy -0.16256 -0.76835) (xy -0.1524 -0.8001) (xy -0.13716 -0.82804)
						(xy -0.11684 -0.85344) (xy -0.09144 -0.87376) (xy -0.0635 -0.889) (xy -0.03175 -0.89916) (xy 0 -0.9017)
						(xy 0.03175 -0.89916) (xy 0.0635 -0.889) (xy 0.09144 -0.87376) (xy 0.11684 -0.85344) (xy 0.13716 -0.82804)
						(xy 0.1524 -0.8001) (xy 0.16256 -0.76835) (xy 0.1651 -0.7366) (xy 0.1651 -0.19685) (xy 0.17272 -0.18923)
						(xy 0.17907 -0.18034) (xy 0.18669 -0.17145) (xy 0.19177 -0.16256) (xy 0.19812 -0.15367) (xy 0.20828 -0.13335)
						(xy 0.21971 -0.10287) (xy 0.22225 -0.09271) (xy 0.22479 -0.08128) (xy 0.22606 -0.07112) (xy 0.2286 -0.05969)
						(xy 0.2286 -0.01651) (xy 0.22606 -0.00508) (xy 0.22479 0.00508) (xy 0.22225 0.01651) (xy 0.21971 0.02667)
						(xy 0.20828 0.05715) (xy 0.19812 0.07747) (xy 0.19177 0.08636) (xy 0.18669 0.09525) (xy 0.17907 0.10414)
						(xy 0.17272 0.11303) (xy 0.1651 0.12065) (xy 0.1651 0.7366) (xy 0.16256 0.76835) (xy 0.1524 0.8001)
						(xy 0.13716 0.82804) (xy 0.11684 0.85344) (xy 0.09144 0.87376) (xy 0.0635 0.889) (xy 0.03175 0.89916)
					)
					(width 0)
					(fill yes)
				)
			)
		)
		(pad "68" smd custom
			(at -11.549888 -4.106672)
			(size 0.1143 0.1143)
			(layers "F.Cu" "F.Mask" "F.Paste")
			(net "M_B_DQ27")
			(options
				(clearance outline)
				(anchor circle)
			)
			(primitives
				(gr_poly
					(pts
						(xy 0 0.9017) (xy -0.03175 0.89916) (xy -0.0635 0.889) (xy -0.09144 0.87376) (xy -0.11684 0.85344)
						(xy -0.13716 0.82804) (xy -0.1524 0.8001) (xy -0.16256 0.76835) (xy -0.1651 0.7366) (xy -0.1651 0.19685)
						(xy -0.17272 0.18923) (xy -0.17907 0.18034) (xy -0.18669 0.17145) (xy -0.19177 0.16256) (xy -0.19812 0.15367)
						(xy -0.20828 0.13335) (xy -0.21971 0.10287) (xy -0.22225 0.09271) (xy -0.22479 0.08128) (xy -0.22606 0.07112)
						(xy -0.2286 0.05969) (xy -0.2286 0.01651) (xy -0.22606 0.00508) (xy -0.22479 -0.00508) (xy -0.22225 -0.01651)
						(xy -0.21971 -0.02667) (xy -0.20828 -0.05715) (xy -0.19812 -0.07747) (xy -0.19177 -0.08636) (xy -0.18669 -0.09525)
						(xy -0.17907 -0.10414) (xy -0.17272 -0.11303) (xy -0.1651 -0.12065) (xy -0.1651 -0.7366) (xy -0.16256 -0.76835)
						(xy -0.1524 -0.8001) (xy -0.13716 -0.82804) (xy -0.11684 -0.85344) (xy -0.09144 -0.87376) (xy -0.0635 -0.889)
						(xy -0.03175 -0.89916) (xy 0 -0.9017) (xy 0.03175 -0.89916) (xy 0.0635 -0.889) (xy 0.09144 -0.87376)
						(xy 0.11684 -0.85344) (xy 0.13716 -0.82804) (xy 0.1524 -0.8001) (xy 0.16256 -0.76835) (xy 0.1651 -0.7366)
						(xy 0.1651 -0.11938) (xy 0.17272 -0.11176) (xy 0.19812 -0.0762) (xy 0.2032 -0.06604) (xy 0.20701 -0.05715)
						(xy 0.21209 -0.04699) (xy 0.2159 -0.03683) (xy 0.21844 -0.02667) (xy 0.22225 -0.01524) (xy 0.22352 -0.00508)
						(xy 0.22606 0.00508) (xy 0.22733 0.01651) (xy 0.22733 0.02667) (xy 0.2286 0.0381) (xy 0.22733 0.04953)
						(xy 0.22733 0.05969) (xy 0.22606 0.07112) (xy 0.22352 0.08128) (xy 0.22225 0.09144) (xy 0.21844 0.10287)
						(xy 0.2159 0.11303) (xy 0.21209 0.12319) (xy 0.20701 0.13335) (xy 0.2032 0.14224) (xy 0.19812 0.1524)
						(xy 0.17272 0.18796) (xy 0.1651 0.19558) (xy 0.1651 0.7366) (xy 0.16256 0.76835) (xy 0.1524 0.8001)
						(xy 0.13716 0.82804) (xy 0.11684 0.85344) (xy 0.09144 0.87376) (xy 0.0635 0.889) (xy 0.03175 0.89916)
					)
					(width 0)
					(fill yes)
				)
			)
		)
		(pad "69" smd custom
			(at -11.249914 4.106672)
			(size 0.1143 0.1143)
			(layers "F.Cu" "F.Mask" "F.Paste")
			(net "M_B_ECC4")
			(options
				(clearance outline)
				(anchor circle)
			)
			(primitives
				(gr_poly
					(pts
						(xy 0 0.9017) (xy -0.03175 0.89916) (xy -0.0635 0.889) (xy -0.09144 0.87376) (xy -0.11684 0.85344)
						(xy -0.13716 0.82804) (xy -0.1524 0.8001) (xy -0.16256 0.76835) (xy -0.1651 0.7366) (xy -0.1651 -0.13462)
						(xy -0.17272 -0.14224) (xy -0.19812 -0.1778) (xy -0.2032 -0.18796) (xy -0.20701 -0.19685) (xy -0.21209 -0.20701)
						(xy -0.2159 -0.21717) (xy -0.21844 -0.22733) (xy -0.22225 -0.23876) (xy -0.22352 -0.24892) (xy -0.22606 -0.25908)
						(xy -0.22733 -0.27051) (xy -0.22733 -0.28067) (xy -0.2286 -0.2921) (xy -0.22733 -0.30353) (xy -0.22733 -0.31369)
						(xy -0.22606 -0.32512) (xy -0.22352 -0.33528) (xy -0.22225 -0.34544) (xy -0.21844 -0.35687) (xy -0.2159 -0.36703)
						(xy -0.21209 -0.37719) (xy -0.20701 -0.38735) (xy -0.2032 -0.39624) (xy -0.19812 -0.4064) (xy -0.17272 -0.44196)
						(xy -0.1651 -0.44958) (xy -0.1651 -0.7366) (xy -0.16256 -0.76835) (xy -0.1524 -0.8001) (xy -0.13716 -0.82804)
						(xy -0.11684 -0.85344) (xy -0.09144 -0.87376) (xy -0.0635 -0.889) (xy -0.03175 -0.89916) (xy 0 -0.9017)
						(xy 0.03175 -0.89916) (xy 0.0635 -0.889) (xy 0.09144 -0.87376) (xy 0.11684 -0.85344) (xy 0.13716 -0.82804)
						(xy 0.1524 -0.8001) (xy 0.16256 -0.76835) (xy 0.1651 -0.7366) (xy 0.1651 -0.44958) (xy 0.17272 -0.44196)
						(xy 0.19812 -0.4064) (xy 0.2032 -0.39624) (xy 0.20701 -0.38735) (xy 0.21209 -0.37719) (xy 0.2159 -0.36703)
						(xy 0.21844 -0.35687) (xy 0.22225 -0.34544) (xy 0.22352 -0.33528) (xy 0.22606 -0.32512) (xy 0.22733 -0.31369)
						(xy 0.22733 -0.30353) (xy 0.2286 -0.2921) (xy 0.22733 -0.28067) (xy 0.22733 -0.27051) (xy 0.22606 -0.25908)
						(xy 0.22352 -0.24892) (xy 0.22225 -0.23876) (xy 0.21844 -0.22733) (xy 0.2159 -0.21717) (xy 0.21209 -0.20701)
						(xy 0.20701 -0.19685) (xy 0.2032 -0.18796) (xy 0.19812 -0.1778) (xy 0.17272 -0.14224) (xy 0.1651 -0.13462)
						(xy 0.1651 0.7366) (xy 0.16256 0.76835) (xy 0.1524 0.8001) (xy 0.13716 0.82804) (xy 0.11684 0.85344)
						(xy 0.09144 0.87376) (xy 0.0635 0.889) (xy 0.03175 0.89916)
					)
					(width 0)
					(fill yes)
				)
			)
		)
	)
)
